(kicad_pcb
	(version 20260206)
	(generator "pcbnew")
	(generator_version "10.0")
	(general
		(thickness 1.6)
		(legacy_teardrops no)
	)
	(paper "A4")
	(title_block
		(title "04192023_DAF0TMB3IC0_F0TG_MB_C_brd_V02_OCP.brd")
		(comment 1 "Grand Teton / footprints 757-761 of 8354")
	)
	(layers
		(0 "F.Cu" signal "TOP")
		(4 "In1.Cu" signal "GND")
		(6 "In2.Cu" signal "IN1")
		(8 "In3.Cu" signal "GND1")
		(10 "In4.Cu" signal "IN2")
		(12 "In5.Cu" signal "GND2")
		(14 "In6.Cu" signal "IN3")
		(16 "In7.Cu" signal "GND3")
		(18 "In8.Cu" signal "VCC")
		(20 "In9.Cu" signal "VCC1")
		(22 "In10.Cu" signal "GND4")
		(24 "In11.Cu" signal "IN4")
		(26 "In12.Cu" signal "GND5")
		(28 "In13.Cu" signal "IN5")
		(30 "In14.Cu" signal "GND6")
		(32 "In15.Cu" signal "IN6")
		(34 "In16.Cu" signal "GND7")
		(2 "B.Cu" signal "BOTTOM")
		(9 "F.Adhes" user "F.Adhesive")
		(11 "B.Adhes" user "B.Adhesive")
		(13 "F.Paste" user "Package Geometry/Pastemask Top")
		(15 "B.Paste" user "Package Geometry/Pastemask Bottom")
		(5 "F.SilkS" user "Ref Des/Silkscreen Top")
		(7 "B.SilkS" user "Ref Des/Silkscreen Bottom")
		(1 "F.Mask" user "Board Geometry/Soldermask Top")
		(3 "B.Mask" user "Board Geometry/Soldermask Bottom")
		(17 "Dwgs.User" user "User.Drawings")
		(19 "Cmts.User" user "User.Comments")
		(21 "Eco1.User" user "User.Eco1")
		(23 "Eco2.User" user "User.Eco2")
		(25 "Edge.Cuts" user "Board Geometry/Outline")
		(27 "Margin" user)
		(31 "F.CrtYd" user "Package Geometry/Place Bound Top")
		(29 "B.CrtYd" user "Package Geometry/Place Bound Bottom")
		(35 "F.Fab" user "Ref Des/Assembly Top")
		(33 "B.Fab" user "Ref Des/Assembly Bottom")
	)
	(footprint ""
		(layer "F.Cu")
		(at 314.965588 -5.077206)
		(property "Reference" "J8069"
			(at -4.58978 1.628648 90)
			(unlocked yes)
			(layer "F.SilkS")
			(effects
				(font
					(size 0.7874 0.5842)
					(thickness 0.1524)
				)
				(justify left)
			)
		)
		(property "Value" ""
			(at 0 0 0)
			(layer "F.Fab")
			(effects
				(font
					(size 1.27 1.27)
				)
			)
		)
		(duplicate_pad_numbers_are_jumpers no)
		(fp_line
			(start -1.2192 -2.06756)
			(end 1.2192 -2.06756)
			(stroke
				(width 0.1524)
				(type default)
			)
			(layer "F.SilkS")
		)
		(fp_line
			(start -1.2192 2.06756)
			(end -1.2192 -2.06756)
			(stroke
				(width 0.1524)
				(type default)
			)
			(layer "F.SilkS")
		)
		(fp_line
			(start 1.2192 -2.06756)
			(end 1.2192 2.06756)
			(stroke
				(width 0.1524)
				(type default)
			)
			(layer "F.SilkS")
		)
		(fp_line
			(start 1.2192 2.06756)
			(end -1.2192 2.06756)
			(stroke
				(width 0.1524)
				(type default)
			)
			(layer "F.SilkS")
		)
		(pad "" np_thru_hole circle
			(at -2.8829 -1.27 270)
			(size 1.0414 1.0414)
			(drill 1.0414)
			(layers "*.Cu" "*.Mask")
			(clearance 0.381)
			(thermal_gap 0.381)
		)
		(pad "" np_thru_hole circle
			(at -2.8829 1.27 270)
			(size 1.0414 1.0414)
			(drill 1.0414)
			(layers "*.Cu" "*.Mask")
			(clearance 0.381)
			(thermal_gap 0.381)
		)
		(pad "" np_thru_hole circle
			(at 3.4671 -1.27 270)
			(size 1.0414 1.0414)
			(drill 1.0414)
			(layers "*.Cu" "*.Mask")
			(clearance 0.381)
			(thermal_gap 0.381)
		)
		(pad "" np_thru_hole circle
			(at 3.4671 1.27 270)
			(size 1.0414 1.0414)
			(drill 1.0414)
			(layers "*.Cu" "*.Mask")
			(clearance 0.381)
			(thermal_gap 0.381)
		)
		(pad "1" smd rect
			(at 0.8255 -0.249936 270)
			(size 0.3048 0.508)
			(layers "F.Cu" "F.Mask" "F.Paste")
			(net "DELTA_L_85_5INCH_TOP_DN")
		)
		(pad "2" smd rect
			(at 0.8255 0.249936 270)
			(size 0.3048 0.508)
			(layers "F.Cu" "F.Mask" "F.Paste")
			(net "DELTA_L_85_5INCH_TOP_DP")
		)
		(pad "3" smd circle
			(at 0 0)
			(size 0 0)
			(layers "F.Cu" "F.Mask" "F.Paste")
			(net "DELTA_L_GND_1")
		)
		(zone
			(layer "F.Cu")
			(hatch none 0.5)
			(connect_pads
				(clearance 0)
			)
			(min_thickness 0.25)
			(keepout
				(tracks not_allowed)
				(vias allowed)
				(pads allowed)
				(copperpour not_allowed)
				(footprints allowed)
			)
			(placement
				(enabled no)
				(sheetname "")
			)
			(fill
				(thermal_gap 0.5)
				(thermal_bridge_width 0.5)
				(island_removal_mode 0)
			)
			(polygon
				(pts
					(xy 316.083188 -5.625846) (xy 316.083188 -5.530342) (xy 315.486288 -5.530342) (xy 315.486288 -5.123942)
					(xy 316.083188 -5.123942) (xy 316.083188 -5.03047) (xy 315.486288 -5.03047) (xy 315.486288 -4.62407)
					(xy 316.083188 -4.62407) (xy 316.083188 -4.528566) (xy 315.384688 -4.528566) (xy 315.384688 -5.625846)
				)
			)
		)
		(zone
			(layers "F.Cu" "B.Cu" "In1.Cu" "In2.Cu" "In3.Cu" "In4.Cu" "In5.Cu" "In6.Cu"
				"In7.Cu" "In8.Cu" "In9.Cu" "In10.Cu" "In11.Cu" "In12.Cu" "In13.Cu" "In14.Cu"
				"In15.Cu" "In16.Cu"
			)
			(hatch none 0.5)
			(connect_pads
				(clearance 0)
			)
			(min_thickness 0.25)
			(keepout
				(tracks not_allowed)
				(vias allowed)
				(pads allowed)
				(copperpour not_allowed)
				(footprints allowed)
			)
			(placement
				(enabled no)
				(sheetname "")
			)
			(fill
				(thermal_gap 0.5)
				(thermal_bridge_width 0.5)
				(island_removal_mode 0)
			)
			(polygon
				(pts
					(arc
						(start 313.009788 -6.347206)
						(mid 311.155588 -6.347206)
						(end 313.009788 -6.347206)
					)
				)
			)
		)
		(zone
			(layers "F.Cu" "B.Cu" "In1.Cu" "In2.Cu" "In3.Cu" "In4.Cu" "In5.Cu" "In6.Cu"
				"In7.Cu" "In8.Cu" "In9.Cu" "In10.Cu" "In11.Cu" "In12.Cu" "In13.Cu" "In14.Cu"
				"In15.Cu" "In16.Cu"
			)
			(hatch none 0.5)
			(connect_pads
				(clearance 0)
			)
			(min_thickness 0.25)
			(keepout
				(tracks not_allowed)
				(vias allowed)
				(pads allowed)
				(copperpour not_allowed)
				(footprints allowed)
			)
			(placement
				(enabled no)
				(sheetname "")
			)
			(fill
				(thermal_gap 0.5)
				(thermal_bridge_width 0.5)
				(island_removal_mode 0)
			)
			(polygon
				(pts
					(arc
						(start 313.009788 -3.807206)
						(mid 311.155588 -3.807206)
						(end 313.009788 -3.807206)
					)
				)
			)
		)
		(zone
			(layers "F.Cu" "B.Cu" "In1.Cu" "In2.Cu" "In3.Cu" "In4.Cu" "In5.Cu" "In6.Cu"
				"In7.Cu" "In8.Cu" "In9.Cu" "In10.Cu" "In11.Cu" "In12.Cu" "In13.Cu" "In14.Cu"
				"In15.Cu" "In16.Cu"
			)
			(hatch none 0.5)
			(connect_pads
				(clearance 0)
			)
			(min_thickness 0.25)
			(keepout
				(tracks not_allowed)
				(vias allowed)
				(pads allowed)
				(copperpour not_allowed)
				(footprints allowed)
			)
			(placement
				(enabled no)
				(sheetname "")
			)
			(fill
				(thermal_gap 0.5)
				(thermal_bridge_width 0.5)
				(island_removal_mode 0)
			)
			(polygon
				(pts
					(arc
						(start 319.359788 -6.347206)
						(mid 317.505588 -6.347206)
						(end 319.359788 -6.347206)
					)
				)
			)
		)
		(zone
			(layers "F.Cu" "B.Cu" "In1.Cu" "In2.Cu" "In3.Cu" "In4.Cu" "In5.Cu" "In6.Cu"
				"In7.Cu" "In8.Cu" "In9.Cu" "In10.Cu" "In11.Cu" "In12.Cu" "In13.Cu" "In14.Cu"
				"In15.Cu" "In16.Cu"
			)
			(hatch none 0.5)
			(connect_pads
				(clearance 0)
			)
			(min_thickness 0.25)
			(keepout
				(tracks not_allowed)
				(vias allowed)
				(pads allowed)
				(copperpour not_allowed)
				(footprints allowed)
			)
			(placement
				(enabled no)
				(sheetname "")
			)
			(fill
				(thermal_gap 0.5)
				(thermal_bridge_width 0.5)
				(island_removal_mode 0)
			)
			(polygon
				(pts
					(arc
						(start 319.359788 -3.807206)
						(mid 317.505588 -3.807206)
						(end 319.359788 -3.807206)
					)
				)
			)
		)
	)
	(footprint ""
		(layer "F.Cu")
		(at 221.67088 -43.525948 180)
		(property "Reference" "R3530"
			(at 0 0 180)
			(layer "F.SilkS")
			(hide yes)
			(effects
				(font
					(size 1.27 1.27)
				)
			)
		)
		(property "Value" ""
			(at 0 0 180)
			(layer "F.Fab")
			(effects
				(font
					(size 1.27 1.27)
				)
			)
		)
		(duplicate_pad_numbers_are_jumpers no)
		(fp_line
			(start 0.7874 0.4064)
			(end -0.7874 0.4064)
			(stroke
				(width 0.1524)
				(type default)
			)
			(layer "F.SilkS")
		)
		(fp_line
			(start 0.7874 -0.4064)
			(end 0.7874 0.4064)
			(stroke
				(width 0.1524)
				(type default)
			)
			(layer "F.SilkS")
		)
		(fp_line
			(start -0.7874 0.4064)
			(end -0.7874 -0.4064)
			(stroke
				(width 0.1524)
				(type default)
			)
			(layer "F.SilkS")
		)
		(fp_line
			(start -0.7874 -0.4064)
			(end 0.7874 -0.4064)
			(stroke
				(width 0.1524)
				(type default)
			)
			(layer "F.SilkS")
		)
		(fp_line
			(start 0.67945 0.3048)
			(end 0.120396 0.3048)
			(stroke
				(width 0.1)
				(type default)
			)
			(layer "F.Fab")
		)
		(fp_line
			(start 0.67945 -0.3048)
			(end 0.67945 0.3048)
			(stroke
				(width 0.1)
				(type default)
			)
			(layer "F.Fab")
		)
		(fp_line
			(start 0.12065 -0.2794)
			(end 0.12065 -0.3048)
			(stroke
				(width 0.1)
				(type default)
			)
			(layer "F.Fab")
		)
		(fp_line
			(start 0.12065 -0.3048)
			(end 0.67945 -0.3048)
			(stroke
				(width 0.1)
				(type default)
			)
			(layer "F.Fab")
		)
		(fp_line
			(start 0.120396 0.3048)
			(end 0.120396 0.2794)
			(stroke
				(width 0.1)
				(type default)
			)
			(layer "F.Fab")
		)
		(fp_line
			(start 0.120396 0.2794)
			(end -0.12065 0.2794)
			(stroke
				(width 0.1)
				(type default)
			)
			(layer "F.Fab")
		)
		(fp_line
			(start -0.12065 0.3048)
			(end -0.67945 0.3048)
			(stroke
				(width 0.1)
				(type default)
			)
			(layer "F.Fab")
		)
		(fp_line
			(start -0.12065 0.2794)
			(end -0.12065 0.3048)
			(stroke
				(width 0.1)
				(type default)
			)
			(layer "F.Fab")
		)
		(fp_line
			(start -0.12065 -0.2794)
			(end 0.12065 -0.2794)
			(stroke
				(width 0.1)
				(type default)
			)
			(layer "F.Fab")
		)
		(fp_line
			(start -0.12065 -0.305054)
			(end -0.12065 -0.2794)
			(stroke
				(width 0.1)
				(type default)
			)
			(layer "F.Fab")
		)
		(fp_line
			(start -0.67945 0.3048)
			(end -0.67945 -0.305054)
			(stroke
				(width 0.1)
				(type default)
			)
			(layer "F.Fab")
		)
		(fp_line
			(start -0.67945 -0.305054)
			(end -0.12065 -0.305054)
			(stroke
				(width 0.1)
				(type default)
			)
			(layer "F.Fab")
		)
		(pad "1" smd circle
			(at -0.40005 0 180)
			(size 0 0)
			(layers "F.Cu" "F.Mask" "F.Paste")
			(net "P3V3_E1S_0")
		)
		(pad "2" smd circle
			(at 0.40005 0 180)
			(size 0 0)
			(layers "F.Cu" "F.Mask" "F.Paste")
			(net "SMB_E1S_3V3AUX_ISO_SCL_R")
		)
	)
	(footprint ""
		(layer "F.Cu")
		(at 312.499248 -23.52929 -90)
		(property "Reference" "R1342"
			(at 0 0 270)
			(layer "F.SilkS")
			(hide yes)
			(effects
				(font
					(size 1.27 1.27)
				)
			)
		)
		(property "Value" ""
			(at 0 0 270)
			(layer "F.Fab")
			(effects
				(font
					(size 1.27 1.27)
				)
			)
		)
		(duplicate_pad_numbers_are_jumpers no)
		(fp_line
			(start -0.7874 0.4064)
			(end -0.7874 -0.4064)
			(stroke
				(width 0.1524)
				(type default)
			)
			(layer "F.SilkS")
		)
		(fp_line
			(start 0.7874 0.4064)
			(end -0.7874 0.4064)
			(stroke
				(width 0.1524)
				(type default)
			)
			(layer "F.SilkS")
		)
		(fp_line
			(start -0.7874 -0.4064)
			(end 0.7874 -0.4064)
			(stroke
				(width 0.1524)
				(type default)
			)
			(layer "F.SilkS")
		)
		(fp_line
			(start 0.7874 -0.4064)
			(end 0.7874 0.4064)
			(stroke
				(width 0.1524)
				(type default)
			)
			(layer "F.SilkS")
		)
		(fp_line
			(start -0.67945 0.3048)
			(end -0.67945 -0.305054)
			(stroke
				(width 0.1)
				(type default)
			)
			(layer "F.Fab")
		)
		(fp_line
			(start -0.12065 0.3048)
			(end -0.67945 0.3048)
			(stroke
				(width 0.1)
				(type default)
			)
			(layer "F.Fab")
		)
		(fp_line
			(start 0.120396 0.3048)
			(end 0.120396 0.2794)
			(stroke
				(width 0.1)
				(type default)
			)
			(layer "F.Fab")
		)
		(fp_line
			(start 0.67945 0.3048)
			(end 0.120396 0.3048)
			(stroke
				(width 0.1)
				(type default)
			)
			(layer "F.Fab")
		)
		(fp_line
			(start -0.12065 0.2794)
			(end -0.12065 0.3048)
			(stroke
				(width 0.1)
				(type default)
			)
			(layer "F.Fab")
		)
		(fp_line
			(start 0.120396 0.2794)
			(end -0.12065 0.2794)
			(stroke
				(width 0.1)
				(type default)
			)
			(layer "F.Fab")
		)
		(fp_line
			(start -0.12065 -0.2794)
			(end 0.12065 -0.2794)
			(stroke
				(width 0.1)
				(type default)
			)
			(layer "F.Fab")
		)
		(fp_line
			(start 0.12065 -0.2794)
			(end 0.12065 -0.3048)
			(stroke
				(width 0.1)
				(type default)
			)
			(layer "F.Fab")
		)
		(fp_line
			(start 0.12065 -0.3048)
			(end 0.67945 -0.3048)
			(stroke
				(width 0.1)
				(type default)
			)
			(layer "F.Fab")
		)
		(fp_line
			(start 0.67945 -0.3048)
			(end 0.67945 0.3048)
			(stroke
				(width 0.1)
				(type default)
			)
			(layer "F.Fab")
		)
		(fp_line
			(start -0.67945 -0.305054)
			(end -0.12065 -0.305054)
			(stroke
				(width 0.1)
				(type default)
			)
			(layer "F.Fab")
		)
		(fp_line
			(start -0.12065 -0.305054)
			(end -0.12065 -0.2794)
			(stroke
				(width 0.1)
				(type default)
			)
			(layer "F.Fab")
		)
		(pad "1" smd circle
			(at -0.40005 0 270)
			(size 0 0)
			(layers "F.Cu" "F.Mask" "F.Paste")
			(net "FW_RECOVERY_R")
		)
		(pad "2" smd circle
			(at 0.40005 0 270)
			(size 0 0)
			(layers "F.Cu" "F.Mask" "F.Paste")
			(net "GND")
		)
	)
	(footprint ""
		(layer "F.Cu")
		(at 109.219238 -41.17975 90)
		(property "Reference" "R6293"
			(at 0 0 90)
			(layer "F.SilkS")
			(hide yes)
			(effects
				(font
					(size 1.27 1.27)
				)
			)
		)
		(property "Value" ""
			(at 0 0 90)
			(layer "F.Fab")
			(effects
				(font
					(size 1.27 1.27)
				)
			)
		)
		(duplicate_pad_numbers_are_jumpers no)
		(fp_line
			(start 0.7874 -0.4064)
			(end 0.7874 0.4064)
			(stroke
				(width 0.1524)
				(type default)
			)
			(layer "F.SilkS")
		)
		(fp_line
			(start -0.7874 -0.4064)
			(end 0.7874 -0.4064)
			(stroke
				(width 0.1524)
				(type default)
			)
			(layer "F.SilkS")
		)
		(fp_line
			(start 0.7874 0.4064)
			(end -0.7874 0.4064)
			(stroke
				(width 0.1524)
				(type default)
			)
			(layer "F.SilkS")
		)
		(fp_line
			(start -0.7874 0.4064)
			(end -0.7874 -0.4064)
			(stroke
				(width 0.1524)
				(type default)
			)
			(layer "F.SilkS")
		)
		(fp_line
			(start -0.12065 -0.305054)
			(end -0.12065 -0.2794)
			(stroke
				(width 0.1)
				(type default)
			)
			(layer "F.Fab")
		)
		(fp_line
			(start -0.67945 -0.305054)
			(end -0.12065 -0.305054)
			(stroke
				(width 0.1)
				(type default)
			)
			(layer "F.Fab")
		)
		(fp_line
			(start 0.67945 -0.3048)
			(end 0.67945 0.3048)
			(stroke
				(width 0.1)
				(type default)
			)
			(layer "F.Fab")
		)
		(fp_line
			(start 0.12065 -0.3048)
			(end 0.67945 -0.3048)
			(stroke
				(width 0.1)
				(type default)
			)
			(layer "F.Fab")
		)
		(fp_line
			(start 0.12065 -0.2794)
			(end 0.12065 -0.3048)
			(stroke
				(width 0.1)
				(type default)
			)
			(layer "F.Fab")
		)
		(fp_line
			(start -0.12065 -0.2794)
			(end 0.12065 -0.2794)
			(stroke
				(width 0.1)
				(type default)
			)
			(layer "F.Fab")
		)
		(fp_line
			(start 0.120396 0.2794)
			(end -0.12065 0.2794)
			(stroke
				(width 0.1)
				(type default)
			)
			(layer "F.Fab")
		)
		(fp_line
			(start -0.12065 0.2794)
			(end -0.12065 0.3048)
			(stroke
				(width 0.1)
				(type default)
			)
			(layer "F.Fab")
		)
		(fp_line
			(start 0.67945 0.3048)
			(end 0.120396 0.3048)
			(stroke
				(width 0.1)
				(type default)
			)
			(layer "F.Fab")
		)
		(fp_line
			(start 0.120396 0.3048)
			(end 0.120396 0.2794)
			(stroke
				(width 0.1)
				(type default)
			)
			(layer "F.Fab")
		)
		(fp_line
			(start -0.12065 0.3048)
			(end -0.67945 0.3048)
			(stroke
				(width 0.1)
				(type default)
			)
			(layer "F.Fab")
		)
		(fp_line
			(start -0.67945 0.3048)
			(end -0.67945 -0.305054)
			(stroke
				(width 0.1)
				(type default)
			)
			(layer "F.Fab")
		)
		(pad "1" smd circle
			(at -0.40005 0 90)
			(size 0 0)
			(layers "F.Cu" "F.Mask" "F.Paste")
			(net "USB_HUB2_TI_GANGED")
		)
		(pad "2" smd circle
			(at 0.40005 0 90)
			(size 0 0)
			(layers "F.Cu" "F.Mask" "F.Paste")
			(net "GND")
		)
	)
	(footprint ""
		(layer "F.Cu")
		(at 402.415502 -416.899344 -90)
		(property "Reference" "C6585"
			(at 0 0 270)
			(layer "F.SilkS")
			(hide yes)
			(effects
				(font
					(size 1.27 1.27)
				)
			)
		)
		(property "Value" ""
			(at 0 0 270)
			(layer "F.Fab")
			(effects
				(font
					(size 1.27 1.27)
				)
			)
		)
		(duplicate_pad_numbers_are_jumpers no)
		(fp_line
			(start -0.299974 0.150114)
			(end -0.299974 -0.150114)
			(stroke
				(width 0.1)
				(type default)
			)
			(layer "F.Fab")
		)
		(fp_line
			(start 0.299974 0.150114)
			(end -0.299974 0.150114)
			(stroke
				(width 0.1)
				(type default)
			)
			(layer "F.Fab")
		)
		(fp_line
			(start -0.299974 -0.150114)
			(end 0.299974 -0.150114)
			(stroke
				(width 0.1)
				(type default)
			)
			(layer "F.Fab")
		)
		(fp_line
			(start 0.299974 -0.150114)
			(end 0.299974 0.150114)
			(stroke
				(width 0.1)
				(type default)
			)
			(layer "F.Fab")
		)
		(pad "1" smd rect
			(at -0.2667 0 270)
			(size 0.3048 0.381)
			(layers "F.Cu" "F.Mask" "F.Paste")
			(net "P5E_CPU0_P2_TX_BUF_C_DP<10>")
		)
		(pad "2" smd rect
			(at 0.2667 0 270)
			(size 0.3048 0.381)
			(layers "F.Cu" "F.Mask" "F.Paste")
			(net "P5E_CPU0_P2_TX_BUF_DP<10>")
		)
	)
)
